# T6G (Grand Teton) — schematic netlist excerpt (pin names and nets, part order shuffled) for the footprints in the layout excerpt that follows; sources: Cadence DE-HDL packaged netlist, KiCad conversion of 04192023_DAF0TMB3IC0_F0TG_MB_C_brd_V02_OCP.brd

R3663  Q_RES  10K 1% CHIP  pkg 0402LF  page 234 : A = P3V3_AUX ; B = USB_HUB_PSELF

X7  TP_TDR_4P_FTS  TP_TDR_4P_DIP EMPTY  pkg TH  page 260
  S1  = TDR_DIFF_80_TOP_DN
  P1  = T1_GND
  P2  = T1_GND
  S2  = TDR_DIFF_80_TOP_DP

(kicad_pcb
	(version 20260206)
	(generator "pcbnew")
	(generator_version "10.0")
	(general
		(thickness 1.6)
		(legacy_teardrops no)
	)
	(paper "A4")
	(title_block
		(title "04192023_DAF0TMB3IC0_F0TG_MB_C_brd_V02_OCP.brd")
		(comment 1 "Grand Teton / footprints 1865-1866 of 8354")
	)
	(layers
		(0 "F.Cu" signal "TOP")
		(4 "In1.Cu" signal "GND")
		(6 "In2.Cu" signal "IN1")
		(8 "In3.Cu" signal "GND1")
		(10 "In4.Cu" signal "IN2")
		(12 "In5.Cu" signal "GND2")
		(14 "In6.Cu" signal "IN3")
		(16 "In7.Cu" signal "GND3")
		(18 "In8.Cu" signal "VCC")
		(20 "In9.Cu" signal "VCC1")
		(22 "In10.Cu" signal "GND4")
		(24 "In11.Cu" signal "IN4")
		(26 "In12.Cu" signal "GND5")
		(28 "In13.Cu" signal "IN5")
		(30 "In14.Cu" signal "GND6")
		(32 "In15.Cu" signal "IN6")
		(34 "In16.Cu" signal "GND7")
		(2 "B.Cu" signal "BOTTOM")
		(9 "F.Adhes" user "F.Adhesive")
		(11 "B.Adhes" user "B.Adhesive")
		(13 "F.Paste" user "Package Geometry/Pastemask Top")
		(15 "B.Paste" user "Package Geometry/Pastemask Bottom")
		(5 "F.SilkS" user "Ref Des/Silkscreen Top")
		(7 "B.SilkS" user "Ref Des/Silkscreen Bottom")
		(1 "F.Mask" user "Board Geometry/Soldermask Top")
		(3 "B.Mask" user "Board Geometry/Soldermask Bottom")
		(17 "Dwgs.User" user "User.Drawings")
		(19 "Cmts.User" user "User.Comments")
		(21 "Eco1.User" user "User.Eco1")
		(23 "Eco2.User" user "User.Eco2")
		(25 "Edge.Cuts" user "Board Geometry/Outline")
		(27 "Margin" user)
		(31 "F.CrtYd" user "Package Geometry/Place Bound Top")
		(29 "B.CrtYd" user "Package Geometry/Place Bound Bottom")
		(35 "F.Fab" user "Ref Des/Assembly Top")
		(33 "B.Fab" user "Ref Des/Assembly Bottom")
	)
	(footprint ""
		(layer "F.Cu")
		(at 21.176996 -97.083626 180)
		(property "Reference" "R3663"
			(at 0 0 180)
			(layer "F.SilkS")
			(hide yes)
			(effects
				(font
					(size 1.27 1.27)
				)
			)
		)
		(property "Value" ""
			(at 0 0 180)
			(layer "F.Fab")
			(effects
				(font
					(size 1.27 1.27)
				)
			)
		)
		(duplicate_pad_numbers_are_jumpers no)
		(fp_line
			(start 0.7874 0.4064)
			(end -0.7874 0.4064)
			(stroke
				(width 0.1524)
				(type default)
			)
			(layer "F.SilkS")
		)
		(fp_line
			(start 0.7874 -0.4064)
			(end 0.7874 0.4064)
			(stroke
				(width 0.1524)
				(type default)
			)
			(layer "F.SilkS")
		)
		(fp_line
			(start -0.7874 0.4064)
			(end -0.7874 -0.4064)
			(stroke
				(width 0.1524)
				(type default)
			)
			(layer "F.SilkS")
		)
		(fp_line
			(start -0.7874 -0.4064)
			(end 0.7874 -0.4064)
			(stroke
				(width 0.1524)
				(type default)
			)
			(layer "F.SilkS")
		)
		(fp_line
			(start 0.67945 0.3048)
			(end 0.120396 0.3048)
			(stroke
				(width 0.1)
				(type default)
			)
			(layer "F.Fab")
		)
		(fp_line
			(start 0.67945 -0.3048)
			(end 0.67945 0.3048)
			(stroke
				(width 0.1)
				(type default)
			)
			(layer "F.Fab")
		)
		(fp_line
			(start 0.12065 -0.2794)
			(end 0.12065 -0.3048)
			(stroke
				(width 0.1)
				(type default)
			)
			(layer "F.Fab")
		)
		(fp_line
			(start 0.12065 -0.3048)
			(end 0.67945 -0.3048)
			(stroke
				(width 0.1)
				(type default)
			)
			(layer "F.Fab")
		)
		(fp_line
			(start 0.120396 0.3048)
			(end 0.120396 0.2794)
			(stroke
				(width 0.1)
				(type default)
			)
			(layer "F.Fab")
		)
		(fp_line
			(start 0.120396 0.2794)
			(end -0.12065 0.2794)
			(stroke
				(width 0.1)
				(type default)
			)
			(layer "F.Fab")
		)
		(fp_line
			(start -0.12065 0.3048)
			(end -0.67945 0.3048)
			(stroke
				(width 0.1)
				(type default)
			)
			(layer "F.Fab")
		)
		(fp_line
			(start -0.12065 0.2794)
			(end -0.12065 0.3048)
			(stroke
				(width 0.1)
				(type default)
			)
			(layer "F.Fab")
		)
		(fp_line
			(start -0.12065 -0.2794)
			(end 0.12065 -0.2794)
			(stroke
				(width 0.1)
				(type default)
			)
			(layer "F.Fab")
		)
		(fp_line
			(start -0.12065 -0.305054)
			(end -0.12065 -0.2794)
			(stroke
				(width 0.1)
				(type default)
			)
			(layer "F.Fab")
		)
		(fp_line
			(start -0.67945 0.3048)
			(end -0.67945 -0.305054)
			(stroke
				(width 0.1)
				(type default)
			)
			(layer "F.Fab")
		)
		(fp_line
			(start -0.67945 -0.305054)
			(end -0.12065 -0.305054)
			(stroke
				(width 0.1)
				(type default)
			)
			(layer "F.Fab")
		)
		(pad "1" smd circle
			(at -0.40005 0 180)
			(size 0 0)
			(layers "F.Cu" "F.Mask" "F.Paste")
			(net "P3V3_AUX")
		)
		(pad "2" smd circle
			(at 0.40005 0 180)
			(size 0 0)
			(layers "F.Cu" "F.Mask" "F.Paste")
			(net "USB_HUB_PSELF")
		)
	)
	(footprint ""
		(layer "F.Cu")
		(at 527.948906 -147.965414 -90)
		(property "Reference" "X7"
			(at -1.890776 3.496818 0)
			(unlocked yes)
			(layer "F.SilkS")
			(effects
				(font
					(size 0.7874 0.5842)
					(thickness 0.1524)
				)
				(justify left)
			)
		)
		(property "Value" ""
			(at 0 0 270)
			(layer "F.Fab")
			(effects
				(font
					(size 1.27 1.27)
				)
			)
		)
		(property "Device Type" "TP_TDR_4P_FTS_TH-TP_TDR_4P_DIP,EMPTY,TP15"
			(at 1.30175 1.27 0)
			(unlocked yes)
			(layer "F.Fab")
			(hide yes)
			(effects
				(font
					(size 0.635 0.4064)
					(thickness 0.1524)
				)
			)
		)
		(property "User Part Number" "N_A"
			(at 1.30175 1.27 0)
			(unlocked yes)
			(layer "Cmts.User")
			(hide yes)
			(effects
				(font
					(size 0.635 0.4064)
					(thickness 0.1524)
				)
			)
		)
		(duplicate_pad_numbers_are_jumpers no)
		(fp_line
			(start 0 3.81)
			(end 2.54 3.81)
			(stroke
				(width 0.1524)
				(type default)
			)
			(layer "F.SilkS")
		)
		(fp_line
			(start 2.54 3.81)
			(end 2.54 3.6703)
			(stroke
				(width 0.1524)
				(type default)
			)
			(layer "F.SilkS")
		)
		(fp_line
			(start 0 3.175)
			(end 0 3.81)
			(stroke
				(width 0.1524)
				(type default)
			)
			(layer "F.SilkS")
		)
		(fp_line
			(start 2.54 1.4097)
			(end 2.54 1.1303)
			(stroke
				(width 0.1524)
				(type default)
			)
			(layer "F.SilkS")
		)
		(fp_line
			(start 0 0.635)
			(end 0 1.905)
			(stroke
				(width 0.1524)
				(type default)
			)
			(layer "F.SilkS")
		)
		(fp_line
			(start 2.54 -1.1303)
			(end 2.54 -1.27)
			(stroke
				(width 0.1524)
				(type default)
			)
			(layer "F.SilkS")
		)
		(fp_line
			(start 0 -1.27)
			(end 0 -0.635)
			(stroke
				(width 0.1524)
				(type default)
			)
			(layer "F.SilkS")
		)
		(fp_line
			(start 2.54 -1.27)
			(end 0 -1.27)
			(stroke
				(width 0.1524)
				(type default)
			)
			(layer "F.SilkS")
		)
		(fp_poly
			(pts
				(xy -0.761746 0) (xy -2.285746 0.762) (xy -2.285746 -0.762)
			)
			(stroke
				(width 0)
				(type default)
			)
			(fill yes)
			(layer "F.SilkS")
		)
		(fp_line
			(start 0 3.81)
			(end 2.54 3.81)
			(stroke
				(width 0.1)
				(type default)
			)
			(layer "F.Fab")
		)
		(fp_line
			(start 2.54 3.81)
			(end 2.54 -1.27)
			(stroke
				(width 0.1)
				(type default)
			)
			(layer "F.Fab")
		)
		(fp_line
			(start 0 -1.27)
			(end 0 3.81)
			(stroke
				(width 0.1)
				(type default)
			)
			(layer "F.Fab")
		)
		(fp_line
			(start 2.54 -1.27)
			(end 0 -1.27)
			(stroke
				(width 0.1)
				(type default)
			)
			(layer "F.Fab")
		)
		(fp_poly
			(pts
				(xy -0.761746 0) (xy -2.285746 -0.762) (xy -2.285746 0.762)
			)
			(stroke
				(width 0)
				(type default)
			)
			(fill yes)
			(layer "F.Fab")
		)
		(pad "1" thru_hole circle
			(at 0 0 270)
			(size 1.0033 1.0033)
			(drill 0.249936)
			(layers "*.Cu" "*.Mask")
			(remove_unused_layers no)
			(net "TDR_DIFF_80_TOP_DN")
			(clearance 0.10795)
			(thermal_gap 0.10795)
			(padstack
				(mode front_inner_back)
				(layer "Inner"
					(shape circle)
					(size 0.8001 0.8001)
					(clearance 0.1524)
				)
				(layer "B.Cu"
					(shape circle)
					(size 1.0033 1.0033)
					(clearance 0.10795)
				)
			)
		)
		(pad "2" thru_hole circle
			(at 2.54 0 270)
			(size 1.9939 1.9939)
			(drill 0.249936)
			(layers "*.Cu" "*.Mask")
			(remove_unused_layers no)
			(net "T1_GND")
			(clearance 0.10795)
			(thermal_gap 0.10795)
			(padstack
				(mode front_inner_back)
				(layer "Inner"
					(shape circle)
					(size 0.8001 0.8001)
					(clearance 0.1524)
				)
				(layer "B.Cu"
					(shape circle)
					(size 1.9939 1.9939)
					(clearance 0.10795)
				)
			)
		)
		(pad "3" thru_hole circle
			(at 2.54 2.54 270)
			(size 1.9939 1.9939)
			(drill 0.249936)
			(layers "*.Cu" "*.Mask")
			(remove_unused_layers no)
			(net "T1_GND")
			(clearance 0.10795)
			(thermal_gap 0.10795)
			(padstack
				(mode front_inner_back)
				(layer "Inner"
					(shape circle)
					(size 0.8001 0.8001)
					(clearance 0.1524)
				)
				(layer "B.Cu"
					(shape circle)
					(size 1.9939 1.9939)
					(clearance 0.10795)
				)
			)
		)
		(pad "4" thru_hole circle
			(at 0 2.54 270)
			(size 1.0033 1.0033)
			(drill 0.249936)
			(layers "*.Cu" "*.Mask")
			(remove_unused_layers no)
			(net "TDR_DIFF_80_TOP_DP")
			(clearance 0.10795)
			(thermal_gap 0.10795)
			(padstack
				(mode front_inner_back)
				(layer "Inner"
					(shape circle)
					(size 0.8001 0.8001)
					(clearance 0.1524)
				)
				(layer "B.Cu"
					(shape circle)
					(size 1.0033 1.0033)
					(clearance 0.10795)
				)
			)
		)
	)
)
